(kicad_pcb
	(version 20260206)
	(generator "pcbnew")
	(generator_version "10.0")
	(general
		(thickness 1.6)
		(legacy_teardrops no)
	)
	(paper "A4")
	(title_block
		(title "04192023_DAF0TMB3IC0_F0TG_MB_C_brd_V02_OCP.brd")
		(comment 1 "Grand Teton / footprints 7215-7221 of 8354")
	)
	(layers
		(0 "F.Cu" signal "TOP")
		(4 "In1.Cu" signal "GND")
		(6 "In2.Cu" signal "IN1")
		(8 "In3.Cu" signal "GND1")
		(10 "In4.Cu" signal "IN2")
		(12 "In5.Cu" signal "GND2")
		(14 "In6.Cu" signal "IN3")
		(16 "In7.Cu" signal "GND3")
		(18 "In8.Cu" signal "VCC")
		(20 "In9.Cu" signal "VCC1")
		(22 "In10.Cu" signal "GND4")
		(24 "In11.Cu" signal "IN4")
		(26 "In12.Cu" signal "GND5")
		(28 "In13.Cu" signal "IN5")
		(30 "In14.Cu" signal "GND6")
		(32 "In15.Cu" signal "IN6")
		(34 "In16.Cu" signal "GND7")
		(2 "B.Cu" signal "BOTTOM")
		(9 "F.Adhes" user "F.Adhesive")
		(11 "B.Adhes" user "B.Adhesive")
		(13 "F.Paste" user "Package Geometry/Pastemask Top")
		(15 "B.Paste" user "Package Geometry/Pastemask Bottom")
		(5 "F.SilkS" user "Ref Des/Silkscreen Top")
		(7 "B.SilkS" user "Ref Des/Silkscreen Bottom")
		(1 "F.Mask" user "Board Geometry/Soldermask Top")
		(3 "B.Mask" user "Board Geometry/Soldermask Bottom")
		(17 "Dwgs.User" user "User.Drawings")
		(19 "Cmts.User" user "User.Comments")
		(21 "Eco1.User" user "User.Eco1")
		(23 "Eco2.User" user "User.Eco2")
		(25 "Edge.Cuts" user "Board Geometry/Outline")
		(27 "Margin" user)
		(31 "F.CrtYd" user "Package Geometry/Place Bound Top")
		(29 "B.CrtYd" user "Package Geometry/Place Bound Bottom")
		(35 "F.Fab" user "Ref Des/Assembly Top")
		(33 "B.Fab" user "Ref Des/Assembly Bottom")
	)
	(footprint ""
		(layer "B.Cu")
		(at 121.691146 -390.560052 90)
		(property "Reference" "C489"
			(at 0 0 90)
			(layer "B.SilkS")
			(hide yes)
			(effects
				(font
					(size 1.27 1.27)
				)
				(justify mirror)
			)
		)
		(property "Value" ""
			(at 0 0 90)
			(layer "B.Fab")
			(effects
				(font
					(size 1.27 1.27)
				)
				(justify mirror)
			)
		)
		(duplicate_pad_numbers_are_jumpers no)
		(fp_line
			(start 0.7874 -0.4064)
			(end -0.7874 -0.4064)
			(stroke
				(width 0.1524)
				(type default)
			)
			(layer "B.SilkS")
		)
		(fp_line
			(start -0.7874 -0.4064)
			(end -0.7874 0.4064)
			(stroke
				(width 0.1524)
				(type default)
			)
			(layer "B.SilkS")
		)
		(fp_line
			(start 0.7874 0.4064)
			(end 0.7874 -0.4064)
			(stroke
				(width 0.1524)
				(type default)
			)
			(layer "B.SilkS")
		)
		(fp_line
			(start -0.7874 0.4064)
			(end 0.7874 0.4064)
			(stroke
				(width 0.1524)
				(type default)
			)
			(layer "B.SilkS")
		)
		(fp_line
			(start 0.67945 -0.305054)
			(end 0.12065 -0.305054)
			(stroke
				(width 0.1)
				(type default)
			)
			(layer "B.Fab")
		)
		(fp_line
			(start 0.12065 -0.305054)
			(end 0.12065 -0.2794)
			(stroke
				(width 0.1)
				(type default)
			)
			(layer "B.Fab")
		)
		(fp_line
			(start -0.12065 -0.3048)
			(end -0.67945 -0.3048)
			(stroke
				(width 0.1)
				(type default)
			)
			(layer "B.Fab")
		)
		(fp_line
			(start -0.67945 -0.3048)
			(end -0.67945 0.3048)
			(stroke
				(width 0.1)
				(type default)
			)
			(layer "B.Fab")
		)
		(fp_line
			(start 0.12065 -0.2794)
			(end -0.12065 -0.2794)
			(stroke
				(width 0.1)
				(type default)
			)
			(layer "B.Fab")
		)
		(fp_line
			(start -0.12065 -0.2794)
			(end -0.12065 -0.3048)
			(stroke
				(width 0.1)
				(type default)
			)
			(layer "B.Fab")
		)
		(fp_line
			(start 0.12065 0.2794)
			(end 0.12065 0.3048)
			(stroke
				(width 0.1)
				(type default)
			)
			(layer "B.Fab")
		)
		(fp_line
			(start -0.120396 0.2794)
			(end 0.12065 0.2794)
			(stroke
				(width 0.1)
				(type default)
			)
			(layer "B.Fab")
		)
		(fp_line
			(start 0.67945 0.3048)
			(end 0.67945 -0.305054)
			(stroke
				(width 0.1)
				(type default)
			)
			(layer "B.Fab")
		)
		(fp_line
			(start 0.12065 0.3048)
			(end 0.67945 0.3048)
			(stroke
				(width 0.1)
				(type default)
			)
			(layer "B.Fab")
		)
		(fp_line
			(start -0.120396 0.3048)
			(end -0.120396 0.2794)
			(stroke
				(width 0.1)
				(type default)
			)
			(layer "B.Fab")
		)
		(fp_line
			(start -0.67945 0.3048)
			(end -0.120396 0.3048)
			(stroke
				(width 0.1)
				(type default)
			)
			(layer "B.Fab")
		)
		(pad "1" smd circle
			(at 0.40005 0 270)
			(size 0 0)
			(layers "B.Cu" "B.Mask" "B.Paste")
			(net "P0V9_CPU1_RT_2D")
		)
		(pad "2" smd circle
			(at -0.40005 0 270)
			(size 0 0)
			(layers "B.Cu" "B.Mask" "B.Paste")
			(net "GND")
		)
	)
	(footprint ""
		(layer "B.Cu")
		(at 52.318412 -388.011162 -90)
		(property "Reference" "C191"
			(at 0 0 90)
			(layer "B.SilkS")
			(hide yes)
			(effects
				(font
					(size 1.27 1.27)
				)
				(justify mirror)
			)
		)
		(property "Value" ""
			(at 0 0 90)
			(layer "B.Fab")
			(effects
				(font
					(size 1.27 1.27)
				)
				(justify mirror)
			)
		)
		(duplicate_pad_numbers_are_jumpers no)
		(fp_line
			(start -0.299974 0.150114)
			(end 0.299974 0.150114)
			(stroke
				(width 0.1)
				(type default)
			)
			(layer "B.Fab")
		)
		(fp_line
			(start 0.299974 0.150114)
			(end 0.299974 -0.150114)
			(stroke
				(width 0.1)
				(type default)
			)
			(layer "B.Fab")
		)
		(fp_line
			(start -0.299974 -0.150114)
			(end -0.299974 0.150114)
			(stroke
				(width 0.1)
				(type default)
			)
			(layer "B.Fab")
		)
		(fp_line
			(start 0.299974 -0.150114)
			(end -0.299974 -0.150114)
			(stroke
				(width 0.1)
				(type default)
			)
			(layer "B.Fab")
		)
		(pad "1" smd rect
			(at 0.2667 0 90)
			(size 0.3048 0.381)
			(layers "B.Cu" "B.Mask" "B.Paste")
			(net "P0V9_CPU1_RT0_2A_2D")
		)
		(pad "2" smd rect
			(at -0.2667 0 90)
			(size 0.3048 0.381)
			(layers "B.Cu" "B.Mask" "B.Paste")
			(net "GND")
		)
	)
	(footprint ""
		(layer "B.Cu")
		(at 54.665118 -346.788994 90)
		(property "Reference" "PC448_1"
			(at 0 0 90)
			(layer "B.SilkS")
			(hide yes)
			(effects
				(font
					(size 1.27 1.27)
				)
				(justify mirror)
			)
		)
		(property "Value" ""
			(at 0 0 90)
			(layer "B.Fab")
			(effects
				(font
					(size 1.27 1.27)
				)
				(justify mirror)
			)
		)
		(duplicate_pad_numbers_are_jumpers no)
		(fp_line
			(start 1.524 -0.762)
			(end -1.524 -0.762)
			(stroke
				(width 0.1524)
				(type default)
			)
			(layer "B.SilkS")
		)
		(fp_line
			(start -1.524 -0.762)
			(end -1.524 0.762)
			(stroke
				(width 0.1524)
				(type default)
			)
			(layer "B.SilkS")
		)
		(fp_line
			(start 1.524 0.762)
			(end 1.524 -0.762)
			(stroke
				(width 0.1524)
				(type default)
			)
			(layer "B.SilkS")
		)
		(fp_line
			(start -1.524 0.762)
			(end 1.524 0.762)
			(stroke
				(width 0.1524)
				(type default)
			)
			(layer "B.SilkS")
		)
		(fp_line
			(start 1.1049 -0.724916)
			(end 1.1049 0.724916)
			(stroke
				(width 0.1)
				(type default)
			)
			(layer "B.Fab")
		)
		(fp_line
			(start -1.1049 -0.724916)
			(end 1.1049 -0.724916)
			(stroke
				(width 0.1)
				(type default)
			)
			(layer "B.Fab")
		)
		(fp_line
			(start 1.1049 0.724916)
			(end -1.1049 0.724916)
			(stroke
				(width 0.1)
				(type default)
			)
			(layer "B.Fab")
		)
		(fp_line
			(start -1.1049 0.724916)
			(end -1.1049 -0.724916)
			(stroke
				(width 0.1)
				(type default)
			)
			(layer "B.Fab")
		)
		(pad "1" smd rect
			(at 0.889 0 90)
			(size 1.016 1.27)
			(layers "B.Cu" "B.Mask" "B.Paste")
			(net "SW_P12V_AUX_PVDDIO_P1_FLT")
		)
		(pad "2" smd rect
			(at -0.889 0 90)
			(size 1.016 1.27)
			(layers "B.Cu" "B.Mask" "B.Paste")
			(net "GND")
		)
	)
	(footprint ""
		(layer "B.Cu")
		(at 428.98695 -40.071548 180)
		(property "Reference" "R1262"
			(at 0 0 0)
			(layer "B.SilkS")
			(hide yes)
			(effects
				(font
					(size 1.27 1.27)
				)
				(justify mirror)
			)
		)
		(property "Value" ""
			(at 0 0 0)
			(layer "B.Fab")
			(effects
				(font
					(size 1.27 1.27)
				)
				(justify mirror)
			)
		)
		(duplicate_pad_numbers_are_jumpers no)
		(fp_line
			(start 0.7874 0.4064)
			(end 0.7874 -0.4064)
			(stroke
				(width 0.1524)
				(type default)
			)
			(layer "B.SilkS")
		)
		(fp_line
			(start 0.7874 -0.4064)
			(end -0.7874 -0.4064)
			(stroke
				(width 0.1524)
				(type default)
			)
			(layer "B.SilkS")
		)
		(fp_line
			(start -0.7874 0.4064)
			(end 0.7874 0.4064)
			(stroke
				(width 0.1524)
				(type default)
			)
			(layer "B.SilkS")
		)
		(fp_line
			(start -0.7874 -0.4064)
			(end -0.7874 0.4064)
			(stroke
				(width 0.1524)
				(type default)
			)
			(layer "B.SilkS")
		)
		(fp_line
			(start 0.67945 0.3048)
			(end 0.67945 -0.305054)
			(stroke
				(width 0.1)
				(type default)
			)
			(layer "B.Fab")
		)
		(fp_line
			(start 0.67945 -0.305054)
			(end 0.12065 -0.305054)
			(stroke
				(width 0.1)
				(type default)
			)
			(layer "B.Fab")
		)
		(fp_line
			(start 0.12065 0.3048)
			(end 0.67945 0.3048)
			(stroke
				(width 0.1)
				(type default)
			)
			(layer "B.Fab")
		)
		(fp_line
			(start 0.12065 0.2794)
			(end 0.12065 0.3048)
			(stroke
				(width 0.1)
				(type default)
			)
			(layer "B.Fab")
		)
		(fp_line
			(start 0.12065 -0.2794)
			(end -0.12065 -0.2794)
			(stroke
				(width 0.1)
				(type default)
			)
			(layer "B.Fab")
		)
		(fp_line
			(start 0.12065 -0.305054)
			(end 0.12065 -0.2794)
			(stroke
				(width 0.1)
				(type default)
			)
			(layer "B.Fab")
		)
		(fp_line
			(start -0.120396 0.3048)
			(end -0.120396 0.2794)
			(stroke
				(width 0.1)
				(type default)
			)
			(layer "B.Fab")
		)
		(fp_line
			(start -0.120396 0.2794)
			(end 0.12065 0.2794)
			(stroke
				(width 0.1)
				(type default)
			)
			(layer "B.Fab")
		)
		(fp_line
			(start -0.12065 -0.2794)
			(end -0.12065 -0.3048)
			(stroke
				(width 0.1)
				(type default)
			)
			(layer "B.Fab")
		)
		(fp_line
			(start -0.12065 -0.3048)
			(end -0.67945 -0.3048)
			(stroke
				(width 0.1)
				(type default)
			)
			(layer "B.Fab")
		)
		(fp_line
			(start -0.67945 0.3048)
			(end -0.120396 0.3048)
			(stroke
				(width 0.1)
				(type default)
			)
			(layer "B.Fab")
		)
		(fp_line
			(start -0.67945 -0.3048)
			(end -0.67945 0.3048)
			(stroke
				(width 0.1)
				(type default)
			)
			(layer "B.Fab")
		)
		(pad "1" smd circle
			(at 0.40005 0)
			(size 0 0)
			(layers "B.Cu" "B.Mask" "B.Paste")
			(net "P1V8_AUX")
		)
		(pad "2" smd circle
			(at -0.40005 0)
			(size 0 0)
			(layers "B.Cu" "B.Mask" "B.Paste")
			(net "BMC_JTAG_SEL")
		)
	)
	(footprint ""
		(layer "B.Cu")
		(at 302.133 -356.997 180)
		(property "Reference" "R8048"
			(at 0 0 0)
			(layer "B.SilkS")
			(hide yes)
			(effects
				(font
					(size 1.27 1.27)
				)
				(justify mirror)
			)
		)
		(property "Value" ""
			(at 0 0 0)
			(layer "B.Fab")
			(effects
				(font
					(size 1.27 1.27)
				)
				(justify mirror)
			)
		)
		(duplicate_pad_numbers_are_jumpers no)
		(fp_line
			(start 0.7874 0.4064)
			(end 0.7874 -0.4064)
			(stroke
				(width 0.1524)
				(type default)
			)
			(layer "B.SilkS")
		)
		(fp_line
			(start 0.7874 -0.4064)
			(end -0.7874 -0.4064)
			(stroke
				(width 0.1524)
				(type default)
			)
			(layer "B.SilkS")
		)
		(fp_line
			(start -0.7874 0.4064)
			(end 0.7874 0.4064)
			(stroke
				(width 0.1524)
				(type default)
			)
			(layer "B.SilkS")
		)
		(fp_line
			(start -0.7874 -0.4064)
			(end -0.7874 0.4064)
			(stroke
				(width 0.1524)
				(type default)
			)
			(layer "B.SilkS")
		)
		(fp_line
			(start 0.67945 0.3048)
			(end 0.67945 -0.305054)
			(stroke
				(width 0.1)
				(type default)
			)
			(layer "B.Fab")
		)
		(fp_line
			(start 0.67945 -0.305054)
			(end 0.12065 -0.305054)
			(stroke
				(width 0.1)
				(type default)
			)
			(layer "B.Fab")
		)
		(fp_line
			(start 0.12065 0.3048)
			(end 0.67945 0.3048)
			(stroke
				(width 0.1)
				(type default)
			)
			(layer "B.Fab")
		)
		(fp_line
			(start 0.12065 0.2794)
			(end 0.12065 0.3048)
			(stroke
				(width 0.1)
				(type default)
			)
			(layer "B.Fab")
		)
		(fp_line
			(start 0.12065 -0.2794)
			(end -0.12065 -0.2794)
			(stroke
				(width 0.1)
				(type default)
			)
			(layer "B.Fab")
		)
		(fp_line
			(start 0.12065 -0.305054)
			(end 0.12065 -0.2794)
			(stroke
				(width 0.1)
				(type default)
			)
			(layer "B.Fab")
		)
		(fp_line
			(start -0.120396 0.3048)
			(end -0.120396 0.2794)
			(stroke
				(width 0.1)
				(type default)
			)
			(layer "B.Fab")
		)
		(fp_line
			(start -0.120396 0.2794)
			(end 0.12065 0.2794)
			(stroke
				(width 0.1)
				(type default)
			)
			(layer "B.Fab")
		)
		(fp_line
			(start -0.12065 -0.2794)
			(end -0.12065 -0.3048)
			(stroke
				(width 0.1)
				(type default)
			)
			(layer "B.Fab")
		)
		(fp_line
			(start -0.12065 -0.3048)
			(end -0.67945 -0.3048)
			(stroke
				(width 0.1)
				(type default)
			)
			(layer "B.Fab")
		)
		(fp_line
			(start -0.67945 0.3048)
			(end -0.120396 0.3048)
			(stroke
				(width 0.1)
				(type default)
			)
			(layer "B.Fab")
		)
		(fp_line
			(start -0.67945 -0.3048)
			(end -0.67945 0.3048)
			(stroke
				(width 0.1)
				(type default)
			)
			(layer "B.Fab")
		)
		(pad "1" smd circle
			(at 0.40005 0)
			(size 0 0)
			(layers "B.Cu" "B.Mask" "B.Paste")
			(net "PVDD18_S5_P0")
		)
		(pad "2" smd circle
			(at -0.40005 0)
			(size 0 0)
			(layers "B.Cu" "B.Mask" "B.Paste")
			(net "SVID_PVDDCR_CPU1_P0_SVC_R")
		)
	)
	(footprint ""
		(layer "B.Cu")
		(at 395.123162 -200.763632 90)
		(property "Reference" "R6135"
			(at 0 0 90)
			(layer "B.SilkS")
			(hide yes)
			(effects
				(font
					(size 1.27 1.27)
				)
				(justify mirror)
			)
		)
		(property "Value" ""
			(at 0 0 90)
			(layer "B.Fab")
			(effects
				(font
					(size 1.27 1.27)
				)
				(justify mirror)
			)
		)
		(duplicate_pad_numbers_are_jumpers no)
		(fp_line
			(start 0.7874 -0.4064)
			(end -0.7874 -0.4064)
			(stroke
				(width 0.1524)
				(type default)
			)
			(layer "B.SilkS")
		)
		(fp_line
			(start -0.7874 -0.4064)
			(end -0.7874 0.4064)
			(stroke
				(width 0.1524)
				(type default)
			)
			(layer "B.SilkS")
		)
		(fp_line
			(start 0.7874 0.4064)
			(end 0.7874 -0.4064)
			(stroke
				(width 0.1524)
				(type default)
			)
			(layer "B.SilkS")
		)
		(fp_line
			(start -0.7874 0.4064)
			(end 0.7874 0.4064)
			(stroke
				(width 0.1524)
				(type default)
			)
			(layer "B.SilkS")
		)
		(fp_line
			(start 0.67945 -0.305054)
			(end 0.12065 -0.305054)
			(stroke
				(width 0.1)
				(type default)
			)
			(layer "B.Fab")
		)
		(fp_line
			(start 0.12065 -0.305054)
			(end 0.12065 -0.2794)
			(stroke
				(width 0.1)
				(type default)
			)
			(layer "B.Fab")
		)
		(fp_line
			(start -0.12065 -0.3048)
			(end -0.67945 -0.3048)
			(stroke
				(width 0.1)
				(type default)
			)
			(layer "B.Fab")
		)
		(fp_line
			(start -0.67945 -0.3048)
			(end -0.67945 0.3048)
			(stroke
				(width 0.1)
				(type default)
			)
			(layer "B.Fab")
		)
		(fp_line
			(start 0.12065 -0.2794)
			(end -0.12065 -0.2794)
			(stroke
				(width 0.1)
				(type default)
			)
			(layer "B.Fab")
		)
		(fp_line
			(start -0.12065 -0.2794)
			(end -0.12065 -0.3048)
			(stroke
				(width 0.1)
				(type default)
			)
			(layer "B.Fab")
		)
		(fp_line
			(start 0.12065 0.2794)
			(end 0.12065 0.3048)
			(stroke
				(width 0.1)
				(type default)
			)
			(layer "B.Fab")
		)
		(fp_line
			(start -0.120396 0.2794)
			(end 0.12065 0.2794)
			(stroke
				(width 0.1)
				(type default)
			)
			(layer "B.Fab")
		)
		(fp_line
			(start 0.67945 0.3048)
			(end 0.67945 -0.305054)
			(stroke
				(width 0.1)
				(type default)
			)
			(layer "B.Fab")
		)
		(fp_line
			(start 0.12065 0.3048)
			(end 0.67945 0.3048)
			(stroke
				(width 0.1)
				(type default)
			)
			(layer "B.Fab")
		)
		(fp_line
			(start -0.120396 0.3048)
			(end -0.120396 0.2794)
			(stroke
				(width 0.1)
				(type default)
			)
			(layer "B.Fab")
		)
		(fp_line
			(start -0.67945 0.3048)
			(end -0.120396 0.3048)
			(stroke
				(width 0.1)
				(type default)
			)
			(layer "B.Fab")
		)
		(pad "1" smd circle
			(at 0.40005 0 270)
			(size 0 0)
			(layers "B.Cu" "B.Mask" "B.Paste")
			(net "FAB_REV_ID0")
		)
		(pad "2" smd circle
			(at -0.40005 0 270)
			(size 0 0)
			(layers "B.Cu" "B.Mask" "B.Paste")
			(net "GND")
		)
	)
	(footprint ""
		(layer "B.Cu")
		(at 135.919718 -9.02589 -90)
		(property "Reference" "R321"
			(at 0 0 90)
			(layer "B.SilkS")
			(hide yes)
			(effects
				(font
					(size 1.27 1.27)
				)
				(justify mirror)
			)
		)
		(property "Value" ""
			(at 0 0 90)
			(layer "B.Fab")
			(effects
				(font
					(size 1.27 1.27)
				)
				(justify mirror)
			)
		)
		(duplicate_pad_numbers_are_jumpers no)
		(fp_line
			(start -0.7874 0.4064)
			(end 0.7874 0.4064)
			(stroke
				(width 0.1524)
				(type default)
			)
			(layer "B.SilkS")
		)
		(fp_line
			(start 0.7874 0.4064)
			(end 0.7874 -0.4064)
			(stroke
				(width 0.1524)
				(type default)
			)
			(layer "B.SilkS")
		)
		(fp_line
			(start -0.7874 -0.4064)
			(end -0.7874 0.4064)
			(stroke
				(width 0.1524)
				(type default)
			)
			(layer "B.SilkS")
		)
		(fp_line
			(start 0.7874 -0.4064)
			(end -0.7874 -0.4064)
			(stroke
				(width 0.1524)
				(type default)
			)
			(layer "B.SilkS")
		)
		(fp_line
			(start -0.67945 0.3048)
			(end -0.120396 0.3048)
			(stroke
				(width 0.1)
				(type default)
			)
			(layer "B.Fab")
		)
		(fp_line
			(start -0.120396 0.3048)
			(end -0.120396 0.2794)
			(stroke
				(width 0.1)
				(type default)
			)
			(layer "B.Fab")
		)
		(fp_line
			(start 0.12065 0.3048)
			(end 0.67945 0.3048)
			(stroke
				(width 0.1)
				(type default)
			)
			(layer "B.Fab")
		)
		(fp_line
			(start 0.67945 0.3048)
			(end 0.67945 -0.305054)
			(stroke
				(width 0.1)
				(type default)
			)
			(layer "B.Fab")
		)
		(fp_line
			(start -0.120396 0.2794)
			(end 0.12065 0.2794)
			(stroke
				(width 0.1)
				(type default)
			)
			(layer "B.Fab")
		)
		(fp_line
			(start 0.12065 0.2794)
			(end 0.12065 0.3048)
			(stroke
				(width 0.1)
				(type default)
			)
			(layer "B.Fab")
		)
		(fp_line
			(start -0.12065 -0.2794)
			(end -0.12065 -0.3048)
			(stroke
				(width 0.1)
				(type default)
			)
			(layer "B.Fab")
		)
		(fp_line
			(start 0.12065 -0.2794)
			(end -0.12065 -0.2794)
			(stroke
				(width 0.1)
				(type default)
			)
			(layer "B.Fab")
		)
		(fp_line
			(start -0.67945 -0.3048)
			(end -0.67945 0.3048)
			(stroke
				(width 0.1)
				(type default)
			)
			(layer "B.Fab")
		)
		(fp_line
			(start -0.12065 -0.3048)
			(end -0.67945 -0.3048)
			(stroke
				(width 0.1)
				(type default)
			)
			(layer "B.Fab")
		)
		(fp_line
			(start 0.12065 -0.305054)
			(end 0.12065 -0.2794)
			(stroke
				(width 0.1)
				(type default)
			)
			(layer "B.Fab")
		)
		(fp_line
			(start 0.67945 -0.305054)
			(end 0.12065 -0.305054)
			(stroke
				(width 0.1)
				(type default)
			)
			(layer "B.Fab")
		)
		(pad "1" smd circle
			(at 0.40005 0 90)
			(size 0 0)
			(layers "B.Cu" "B.Mask" "B.Paste")
			(net "SCM_IRQ_N")
		)
		(pad "2" smd circle
			(at -0.40005 0 90)
			(size 0 0)
			(layers "B.Cu" "B.Mask" "B.Paste")
			(net "IRQ0_A56")
		)
	)
)
